(kicad_pcb
	(version 20260206)
	(generator "pcbnew")
	(generator_version "10.0")
	(general
		(thickness 1.6)
		(legacy_teardrops no)
	)
	(paper "A4")
	(title_block
		(title "Bryce Canyon_R.DPB_16317-1_OCP.brd")
		(comment 1 "Bryce Canyon / footprints 166-173 of 2099")
	)
	(layers
		(0 "F.Cu" signal "TOP")
		(4 "In1.Cu" signal "L2GND")
		(6 "In2.Cu" signal "L3")
		(8 "In3.Cu" signal "L4VCC")
		(10 "In4.Cu" signal "L5VCC")
		(12 "In5.Cu" signal "L6")
		(14 "In6.Cu" signal "L7GND")
		(2 "B.Cu" signal "BOTTOM")
		(9 "F.Adhes" user "F.Adhesive")
		(11 "B.Adhes" user "B.Adhesive")
		(13 "F.Paste" user "Package Geometry/Pastemask Top")
		(15 "B.Paste" user "Package Geometry/Pastemask Bottom")
		(5 "F.SilkS" user "Ref Des/Silkscreen Top")
		(7 "B.SilkS" user "Ref Des/Silkscreen Bottom")
		(1 "F.Mask" user "Board Geometry/Soldermask Top")
		(3 "B.Mask" user "Board Geometry/Soldermask Bottom")
		(17 "Dwgs.User" user "User.Drawings")
		(19 "Cmts.User" user "User.Comments")
		(21 "Eco1.User" user "User.Eco1")
		(23 "Eco2.User" user "User.Eco2")
		(25 "Edge.Cuts" user "Board Geometry/Outline")
		(27 "Margin" user)
		(31 "F.CrtYd" user "Package Geometry/Place Bound Top")
		(29 "B.CrtYd" user "Package Geometry/Place Bound Bottom")
		(35 "F.Fab" user "Ref Des/Assembly Top")
		(33 "B.Fab" user "Ref Des/Assembly Bottom")
	)
	(footprint ""
		(layer "F.Cu")
		(at 394.462 -12.827 -90)
		(property "Reference" "Q167"
			(at 0 0 270)
			(layer "F.SilkS")
			(hide yes)
			(effects
				(font
					(size 1.27 1.27)
				)
			)
		)
		(property "Value" "2N7002KDW-GP"
			(at -2.3622 -8.2042 270)
			(unlocked yes)
			(layer "F.Fab")
			(hide yes)
			(effects
				(font
					(size 1.016 1.016)
					(thickness 0.1524)
				)
			)
		)
		(property "Device Type" "SOT-363H44"
			(at -2.3622 -10.1092 270)
			(unlocked yes)
			(layer "F.Fab")
			(hide yes)
			(effects
				(font
					(size 1.016 1.016)
					(thickness 0.1524)
				)
			)
		)
		(duplicate_pad_numbers_are_jumpers no)
		(fp_line
			(start -1.4478 1.7018)
			(end 1.4478 1.7018)
			(stroke
				(width 0.1524)
				(type default)
			)
			(layer "F.SilkS")
		)
		(fp_line
			(start 1.4478 1.7018)
			(end 1.4478 -1.7018)
			(stroke
				(width 0.1524)
				(type default)
			)
			(layer "F.SilkS")
		)
		(fp_line
			(start -1.27 1.524)
			(end -1.27 0.6604)
			(stroke
				(width 0.4826)
				(type default)
			)
			(layer "F.SilkS")
		)
		(fp_line
			(start -1.4478 -1.7018)
			(end -1.4478 1.7018)
			(stroke
				(width 0.1524)
				(type default)
			)
			(layer "F.SilkS")
		)
		(fp_line
			(start 1.4478 -1.7018)
			(end -1.4478 -1.7018)
			(stroke
				(width 0.1524)
				(type default)
			)
			(layer "F.SilkS")
		)
		(fp_poly
			(pts
				(xy -1.524 -1.778) (xy 1.524 -1.778) (xy 1.524 1.778) (xy -1.524 1.778)
			)
			(stroke
				(width 0)
				(type default)
			)
			(fill no)
			(layer "F.CrtYd")
		)
		(fp_poly
			(pts
				(xy -1.524 -1.778) (xy 1.524 -1.778) (xy 1.524 1.778) (xy -1.524 1.778)
			)
			(stroke
				(width 0)
				(type default)
			)
			(fill no)
			(layer "F.Fab")
		)
		(pad "1" smd rect
			(at -0.65024 0.9398 270)
			(size 0.4064 1.016)
			(layers "F.Cu" "F.Mask" "F.Paste")
			(net "GND")
		)
		(pad "2" smd rect
			(at 0 0.9398 270)
			(size 0.4064 1.016)
			(layers "F.Cu" "F.Mask" "F.Paste")
			(net "SW_PWR_R_HDD32")
		)
		(pad "3" smd rect
			(at 0.65024 0.9398 270)
			(size 0.4064 1.016)
			(layers "F.Cu" "F.Mask" "F.Paste")
			(net "SW_HDD_P32")
		)
		(pad "4" smd rect
			(at 0.65024 -0.9398 270)
			(size 0.4064 1.016)
			(layers "F.Cu" "F.Mask" "F.Paste")
			(net "GND")
		)
		(pad "5" smd rect
			(at 0 -0.9398 270)
			(size 0.4064 1.016)
			(layers "F.Cu" "F.Mask" "F.Paste")
			(net "SW_HDD_G32")
		)
		(pad "6" smd rect
			(at -0.65024 -0.9398 270)
			(size 0.4064 1.016)
			(layers "F.Cu" "F.Mask" "F.Paste")
			(net "SW_HDD_R32")
		)
	)
	(footprint ""
		(layer "F.Cu")
		(at 404.400004 -23.999952)
		(property "Reference" ""
			(at 0 0 0)
			(layer "F.SilkS")
			(hide yes)
			(effects
				(font
					(size 1.27 1.27)
				)
			)
		)
		(property "Value" "*"
			(at -6.3373 -0.4572 0)
			(unlocked yes)
			(layer "F.Fab")
			(hide yes)
			(effects
				(font
					(size 1.016 1.016)
					(thickness 0.1524)
				)
			)
		)
		(duplicate_pad_numbers_are_jumpers no)
		(fp_poly
			(pts
				(arc
					(start 5.0673 0)
					(mid -5.0673 0)
					(end 5.0673 0)
				)
			)
			(stroke
				(width 0)
				(type default)
			)
			(fill no)
			(layer "B.CrtYd")
		)
		(fp_poly
			(pts
				(arc
					(start 5.0673 0)
					(mid -5.0673 0)
					(end 5.0673 0)
				)
			)
			(stroke
				(width 0)
				(type default)
			)
			(fill no)
			(layer "F.CrtYd")
		)
		(fp_poly
			(pts
				(arc
					(start 5.0673 0)
					(mid -5.0673 0)
					(end 5.0673 0)
				)
			)
			(stroke
				(width 0)
				(type default)
			)
			(fill no)
			(layer "B.Fab")
		)
		(fp_poly
			(pts
				(arc
					(start 5.0673 0)
					(mid -5.0673 0)
					(end 5.0673 0)
				)
			)
			(stroke
				(width 0)
				(type default)
			)
			(fill no)
			(layer "F.Fab")
		)
		(pad "1" thru_hole circle
			(at 0 0)
			(size 9.525 9.525)
			(drill 3.556)
			(layers "*.Cu" "*.Mask")
			(remove_unused_layers no)
			(net "Net_33")
			(clearance -2.4765)
			(thermal_gap 0.3048)
			(padstack
				(mode front_inner_back)
				(layer "Inner"
					(shape circle)
					(size 3.9624 3.9624)
					(clearance 0.3048)
				)
				(layer "B.Cu"
					(shape circle)
					(size 9.525 9.525)
					(clearance -2.4765)
				)
			)
		)
		(zone
			(layers "F.Cu" "B.Cu" "In1.Cu" "In2.Cu" "In3.Cu" "In4.Cu" "In5.Cu" "In6.Cu")
			(hatch none 0.5)
			(connect_pads
				(clearance 0)
			)
			(min_thickness 0.25)
			(keepout
				(tracks not_allowed)
				(vias allowed)
				(pads allowed)
				(copperpour not_allowed)
				(footprints allowed)
			)
			(placement
				(enabled no)
				(sheetname "")
			)
			(fill
				(thermal_gap 0.5)
				(thermal_bridge_width 0.5)
				(island_removal_mode 0)
			)
			(polygon
				(pts
					(arc
						(start 409.162504 -23.999952)
						(mid 399.637504 -23.999952)
						(end 409.162504 -23.999952)
					)
				)
			)
		)
	)
	(footprint ""
		(layer "F.Cu")
		(at 109.474 -255.524 90)
		(property "Reference" "C78"
			(at 0 0 90)
			(layer "F.SilkS")
			(hide yes)
			(effects
				(font
					(size 1.27 1.27)
				)
			)
		)
		(property "Value" "SCD033U25V2KX-GP"
			(at 1.1811 -2.7051 90)
			(unlocked yes)
			(layer "F.Fab")
			(hide yes)
			(effects
				(font
					(size 1.016 1.016)
					(thickness 0.1524)
				)
			)
		)
		(property "Device Type" "C402H22"
			(at 1.1811 -4.2291 90)
			(unlocked yes)
			(layer "F.Fab")
			(hide yes)
			(effects
				(font
					(size 1.016 1.016)
					(thickness 0.1524)
				)
			)
		)
		(duplicate_pad_numbers_are_jumpers no)
		(fp_rect
			(start -0.4318 0.9525)
			(end 0.4318 -0.9525)
			(stroke
				(width 0)
				(type default)
			)
			(fill no)
			(layer "F.CrtYd")
		)
		(fp_rect
			(start -0.4318 0.9525)
			(end 0.4318 -0.9525)
			(stroke
				(width 0)
				(type default)
			)
			(fill no)
			(layer "F.Fab")
		)
		(pad "1" smd custom
			(at 0 -0.4445 90)
			(size 0.1524 0.1524)
			(layers "F.Cu" "F.Mask" "F.Paste")
			(net "P12V_B")
			(options
				(clearance outline)
				(anchor circle)
			)
			(primitives
				(gr_poly
					(pts
						(arc
							(start 0.3048 -0.2032)
							(mid 0.275042 -0.275042)
							(end 0.2032 -0.3048)
						)
						(arc
							(start -0.2032 -0.3048)
							(mid -0.275042 -0.275042)
							(end -0.3048 -0.2032)
						)
						(arc
							(start -0.3048 0.2032)
							(mid -0.275042 0.275042)
							(end -0.2032 0.3048)
						)
						(arc
							(start 0.2032 0.3048)
							(mid 0.275042 0.275042)
							(end 0.3048 0.2032)
						)
					)
					(width 0)
					(fill yes)
				)
			)
		)
		(pad "2" smd custom
			(at 0 0.4445 90)
			(size 0.1524 0.1524)
			(layers "F.Cu" "F.Mask" "F.Paste")
			(net "SW_HDD_N3")
			(options
				(clearance outline)
				(anchor circle)
			)
			(primitives
				(gr_poly
					(pts
						(arc
							(start 0.3048 -0.2032)
							(mid 0.275042 -0.275042)
							(end 0.2032 -0.3048)
						)
						(arc
							(start -0.2032 -0.3048)
							(mid -0.275042 -0.275042)
							(end -0.3048 -0.2032)
						)
						(arc
							(start -0.3048 0.2032)
							(mid -0.275042 0.275042)
							(end -0.2032 0.3048)
						)
						(arc
							(start 0.2032 0.3048)
							(mid 0.275042 0.275042)
							(end 0.3048 0.2032)
						)
					)
					(width 0)
					(fill yes)
				)
			)
		)
	)
	(footprint ""
		(layer "F.Cu")
		(at 444.148972 -119.184928 -90)
		(property "Reference" "R1159"
			(at 0 0 270)
			(layer "F.SilkS")
			(hide yes)
			(effects
				(font
					(size 1.27 1.27)
				)
			)
		)
		(property "Value" "10KR2F-2-GP"
			(at 0.064008 -3.993896 270)
			(unlocked yes)
			(layer "F.Fab")
			(hide yes)
			(effects
				(font
					(size 1.016 1.016)
					(thickness 0.1524)
				)
			)
		)
		(property "Device Type" "R402H16"
			(at 0.064008 -5.517896 270)
			(unlocked yes)
			(layer "F.Fab")
			(hide yes)
			(effects
				(font
					(size 1.016 1.016)
					(thickness 0.1524)
				)
			)
		)
		(duplicate_pad_numbers_are_jumpers no)
		(fp_line
			(start -0.508 -0.9398)
			(end -0.508 0.9398)
			(stroke
				(width 0.1524)
				(type default)
			)
			(layer "F.SilkS")
		)
		(fp_line
			(start 0.508 -0.9398)
			(end -0.508 -0.9398)
			(stroke
				(width 0.1524)
				(type default)
			)
			(layer "F.SilkS")
		)
		(fp_rect
			(start -0.508 0.9398)
			(end 0.508 -0.9398)
			(stroke
				(width 0)
				(type default)
			)
			(fill no)
			(layer "F.CrtYd")
		)
		(fp_rect
			(start -0.508 0.9398)
			(end 0.508 -0.9398)
			(stroke
				(width 0)
				(type default)
			)
			(fill no)
			(layer "F.Fab")
		)
		(pad "1" smd custom
			(at 0 -0.4445 270)
			(size 0.1397 0.1397)
			(layers "F.Cu" "F.Mask" "F.Paste")
			(net "P5V_B_4")
			(options
				(clearance outline)
				(anchor circle)
			)
			(primitives
				(gr_poly
					(pts
						(arc
							(start -0.1778 -0.2794)
							(mid -0.249642 -0.249642)
							(end -0.2794 -0.1778)
						)
						(arc
							(start -0.2794 0.1778)
							(mid -0.249642 0.249642)
							(end -0.1778 0.2794)
						)
						(arc
							(start 0.1778 0.2794)
							(mid 0.249642 0.249642)
							(end 0.2794 0.1778)
						)
						(arc
							(start 0.2794 -0.1778)
							(mid 0.249642 -0.249642)
							(end 0.1778 -0.2794)
						)
					)
					(width 0)
					(fill yes)
				)
			)
		)
		(pad "2" smd custom
			(at 0 0.4445 270)
			(size 0.1397 0.1397)
			(layers "F.Cu" "F.Mask" "F.Paste")
			(net "P5V_B_4_PGOOD")
			(options
				(clearance outline)
				(anchor circle)
			)
			(primitives
				(gr_poly
					(pts
						(arc
							(start -0.1778 -0.2794)
							(mid -0.249642 -0.249642)
							(end -0.2794 -0.1778)
						)
						(arc
							(start -0.2794 0.1778)
							(mid -0.249642 0.249642)
							(end -0.1778 0.2794)
						)
						(arc
							(start 0.1778 0.2794)
							(mid 0.249642 0.249642)
							(end 0.2794 0.1778)
						)
						(arc
							(start 0.2794 -0.1778)
							(mid 0.249642 -0.249642)
							(end 0.1778 -0.2794)
						)
					)
					(width 0)
					(fill yes)
				)
			)
		)
	)
	(footprint ""
		(layer "F.Cu")
		(at 444.3222 -261.3406)
		(property "Reference" "R321"
			(at 0 0 0)
			(layer "F.SilkS")
			(hide yes)
			(effects
				(font
					(size 1.27 1.27)
				)
			)
		)
		(property "Value" "220R3F-1-GP"
			(at -0.0254 -2.5146 0)
			(unlocked yes)
			(layer "F.Fab")
			(hide yes)
			(effects
				(font
					(size 1.016 1.016)
					(thickness 0.1524)
				)
			)
		)
		(property "Device Type" "R603H22"
			(at -0.0254 -4.0386 0)
			(unlocked yes)
			(layer "F.Fab")
			(hide yes)
			(effects
				(font
					(size 1.016 1.016)
					(thickness 0.1524)
				)
			)
		)
		(duplicate_pad_numbers_are_jumpers no)
		(fp_line
			(start -0.4826 0)
			(end -0.2032 0)
			(stroke
				(width 0.2032)
				(type default)
			)
			(layer "F.SilkS")
		)
		(fp_line
			(start 0.2032 0)
			(end 0.4826 0)
			(stroke
				(width 0.2032)
				(type default)
			)
			(layer "F.SilkS")
		)
		(fp_rect
			(start -0.5842 1.3335)
			(end 0.5842 -1.3335)
			(stroke
				(width 0)
				(type default)
			)
			(fill no)
			(layer "F.CrtYd")
		)
		(fp_rect
			(start -0.5842 1.3335)
			(end 0.5842 -1.3335)
			(stroke
				(width 0)
				(type default)
			)
			(fill no)
			(layer "F.Fab")
		)
		(pad "1" smd custom
			(at 0 -0.762)
			(size 0.2159 0.2159)
			(layers "F.Cu" "F.Mask" "F.Paste")
			(net "HDD_PRSNT_10")
			(options
				(clearance outline)
				(anchor circle)
			)
			(primitives
				(gr_poly
					(pts
						(arc
							(start -0.3302 -0.4318)
							(mid -0.402042 -0.402042)
							(end -0.4318 -0.3302)
						)
						(arc
							(start -0.4318 0.3302)
							(mid -0.402042 0.402042)
							(end -0.3302 0.4318)
						)
						(arc
							(start 0.3302 0.4318)
							(mid 0.402042 0.402042)
							(end 0.4318 0.3302)
						)
						(arc
							(start 0.4318 -0.3302)
							(mid 0.402042 -0.402042)
							(end 0.3302 -0.4318)
						)
					)
					(width 0)
					(fill yes)
				)
			)
		)
		(pad "2" smd custom
			(at 0 0.762)
			(size 0.2159 0.2159)
			(layers "F.Cu" "F.Mask" "F.Paste")
			(net "DRIVE_B_10_INS")
			(options
				(clearance outline)
				(anchor circle)
			)
			(primitives
				(gr_poly
					(pts
						(arc
							(start -0.3302 -0.4318)
							(mid -0.402042 -0.402042)
							(end -0.4318 -0.3302)
						)
						(arc
							(start -0.4318 0.3302)
							(mid -0.402042 0.402042)
							(end -0.3302 0.4318)
						)
						(arc
							(start 0.3302 0.4318)
							(mid 0.402042 0.402042)
							(end 0.4318 0.3302)
						)
						(arc
							(start 0.4318 -0.3302)
							(mid 0.402042 -0.402042)
							(end 0.3302 -0.4318)
						)
					)
					(width 0)
					(fill yes)
				)
			)
		)
	)
	(footprint ""
		(layer "F.Cu")
		(at 265.43 -358.267 90)
		(property "Reference" "D51"
			(at 0 0 90)
			(layer "F.SilkS")
			(hide yes)
			(effects
				(font
					(size 1.27 1.27)
				)
			)
		)
		(property "Value" "MMPZ5228BPT-GP"
			(at 0 -6.7818 90)
			(unlocked yes)
			(layer "F.Fab")
			(hide yes)
			(effects
				(font
					(size 1.016 1.016)
					(thickness 0.1524)
				)
			)
		)
		(property "Device Type" "SOD323AKH40"
			(at 0 -8.6868 90)
			(unlocked yes)
			(layer "F.Fab")
			(hide yes)
			(effects
				(font
					(size 1.016 1.016)
					(thickness 0.1524)
				)
			)
		)
		(duplicate_pad_numbers_are_jumpers no)
		(fp_line
			(start 0.889 -1.9304)
			(end 0.889 2.159)
			(stroke
				(width 0.1524)
				(type default)
			)
			(layer "F.SilkS")
		)
		(fp_line
			(start -0.889 -1.9304)
			(end 0.889 -1.9304)
			(stroke
				(width 0.1524)
				(type default)
			)
			(layer "F.SilkS")
		)
		(fp_line
			(start 0.762 2.0574)
			(end -0.762 2.0574)
			(stroke
				(width 0.508)
				(type default)
			)
			(layer "F.SilkS")
		)
		(fp_line
			(start 0.889 2.159)
			(end -0.889 2.159)
			(stroke
				(width 0.1524)
				(type default)
			)
			(layer "F.SilkS")
		)
		(fp_line
			(start -0.889 2.159)
			(end -0.889 -1.9304)
			(stroke
				(width 0.1524)
				(type default)
			)
			(layer "F.SilkS")
		)
		(fp_rect
			(start -1.016 2.3114)
			(end 1.016 -2.0066)
			(stroke
				(width 0)
				(type default)
			)
			(fill no)
			(layer "F.CrtYd")
		)
		(fp_poly
			(pts
				(xy -1.016 -2.0066) (xy 1.016 -2.0066) (xy 1.016 2.3114) (xy -1.016 2.3114)
			)
			(stroke
				(width 0)
				(type default)
			)
			(fill no)
			(layer "F.Fab")
		)
		(pad "A" smd rect
			(at 0 -1.143 90)
			(size 0.5588 1.016)
			(layers "F.Cu" "F.Mask" "F.Paste")
			(net "GND")
		)
		(pad "K" smd rect
			(at 0 1.143 90)
			(size 0.5588 1.016)
			(layers "F.Cu" "F.Mask" "F.Paste")
			(net "VCCP_IN")
		)
	)
	(footprint ""
		(layer "F.Cu")
		(at 394.6398 -134.5692 90)
		(property "Reference" "R537"
			(at 0 0 90)
			(layer "F.SilkS")
			(hide yes)
			(effects
				(font
					(size 1.27 1.27)
				)
			)
		)
		(property "Value" "4K7R2J-2-GP"
			(at 0.064008 -3.993896 90)
			(unlocked yes)
			(layer "F.Fab")
			(hide yes)
			(effects
				(font
					(size 1.016 1.016)
					(thickness 0.1524)
				)
			)
		)
		(property "Device Type" "R402H16"
			(at 0.064008 -5.517896 90)
			(unlocked yes)
			(layer "F.Fab")
			(hide yes)
			(effects
				(font
					(size 1.016 1.016)
					(thickness 0.1524)
				)
			)
		)
		(duplicate_pad_numbers_are_jumpers no)
		(fp_line
			(start 0.508 -0.9398)
			(end -0.508 -0.9398)
			(stroke
				(width 0.1524)
				(type default)
			)
			(layer "F.SilkS")
		)
		(fp_line
			(start -0.508 -0.9398)
			(end -0.508 0.9398)
			(stroke
				(width 0.1524)
				(type default)
			)
			(layer "F.SilkS")
		)
		(fp_rect
			(start -0.508 0.9398)
			(end 0.508 -0.9398)
			(stroke
				(width 0)
				(type default)
			)
			(fill no)
			(layer "F.CrtYd")
		)
		(fp_rect
			(start -0.508 0.9398)
			(end 0.508 -0.9398)
			(stroke
				(width 0)
				(type default)
			)
			(fill no)
			(layer "F.Fab")
		)
		(pad "1" smd custom
			(at 0 -0.4445 90)
			(size 0.1397 0.1397)
			(layers "F.Cu" "F.Mask" "F.Paste")
			(net "P12V_B")
			(options
				(clearance outline)
				(anchor circle)
			)
			(primitives
				(gr_poly
					(pts
						(arc
							(start -0.1778 -0.2794)
							(mid -0.249642 -0.249642)
							(end -0.2794 -0.1778)
						)
						(arc
							(start -0.2794 0.1778)
							(mid -0.249642 0.249642)
							(end -0.1778 0.2794)
						)
						(arc
							(start 0.1778 0.2794)
							(mid 0.249642 0.249642)
							(end 0.2794 0.1778)
						)
						(arc
							(start 0.2794 -0.1778)
							(mid 0.249642 -0.249642)
							(end 0.1778 -0.2794)
						)
					)
					(width 0)
					(fill yes)
				)
			)
		)
		(pad "2" smd custom
			(at 0 0.4445 90)
			(size 0.1397 0.1397)
			(layers "F.Cu" "F.Mask" "F.Paste")
			(net "SW_HDD_P20")
			(options
				(clearance outline)
				(anchor circle)
			)
			(primitives
				(gr_poly
					(pts
						(arc
							(start -0.1778 -0.2794)
							(mid -0.249642 -0.249642)
							(end -0.2794 -0.1778)
						)
						(arc
							(start -0.2794 0.1778)
							(mid -0.249642 0.249642)
							(end -0.1778 0.2794)
						)
						(arc
							(start 0.1778 0.2794)
							(mid 0.249642 0.249642)
							(end 0.2794 0.1778)
						)
						(arc
							(start 0.2794 -0.1778)
							(mid 0.249642 -0.249642)
							(end 0.1778 -0.2794)
						)
					)
					(width 0)
					(fill yes)
				)
			)
		)
	)
	(footprint ""
		(layer "F.Cu")
		(at 400.431 -248.793 90)
		(property "Reference" "D8"
			(at 0 0 90)
			(layer "F.SilkS")
			(hide yes)
			(effects
				(font
					(size 1.27 1.27)
				)
			)
		)
		(property "Value" "RB551V30-GP"
			(at 0 -6.7818 90)
			(unlocked yes)
			(layer "F.Fab")
			(hide yes)
			(effects
				(font
					(size 1.016 1.016)
					(thickness 0.1524)
				)
			)
		)
		(property "Device Type" "SOD323AKH38"
			(at 0 -8.6868 90)
			(unlocked yes)
			(layer "F.Fab")
			(hide yes)
			(effects
				(font
					(size 1.016 1.016)
					(thickness 0.1524)
				)
			)
		)
		(duplicate_pad_numbers_are_jumpers no)
		(fp_line
			(start 0.889 -1.9304)
			(end 0.889 2.159)
			(stroke
				(width 0.1524)
				(type default)
			)
			(layer "F.SilkS")
		)
		(fp_line
			(start -0.889 -1.9304)
			(end 0.889 -1.9304)
			(stroke
				(width 0.1524)
				(type default)
			)
			(layer "F.SilkS")
		)
		(fp_line
			(start 0.762 2.0574)
			(end -0.762 2.0574)
			(stroke
				(width 0.508)
				(type default)
			)
			(layer "F.SilkS")
		)
		(fp_line
			(start 0.889 2.159)
			(end -0.889 2.159)
			(stroke
				(width 0.1524)
				(type default)
			)
			(layer "F.SilkS")
		)
		(fp_line
			(start -0.889 2.159)
			(end -0.889 -1.9304)
			(stroke
				(width 0.1524)
				(type default)
			)
			(layer "F.SilkS")
		)
		(fp_rect
			(start -1.016 2.3114)
			(end 1.016 -2.0066)
			(stroke
				(width 0)
				(type default)
			)
			(fill no)
			(layer "F.CrtYd")
		)
		(fp_poly
			(pts
				(xy -1.016 -2.0066) (xy 1.016 -2.0066) (xy 1.016 2.3114) (xy -1.016 2.3114)
			)
			(stroke
				(width 0)
				(type default)
			)
			(fill no)
			(layer "F.Fab")
		)
		(pad "A" smd rect
			(at 0 -1.143 90)
			(size 0.5588 1.016)
			(layers "F.Cu" "F.Mask" "F.Paste")
			(net "SW_HDD_R8")
		)
		(pad "K" smd rect
			(at 0 1.143 90)
			(size 0.5588 1.016)
			(layers "F.Cu" "F.Mask" "F.Paste")
			(net "SW_HDD_N8")
		)
	)
)
